(kicad_pcb
	(version 20260206)
	(generator "pcbnew")
	(generator_version "10.0")
	(general
		(thickness 1.6)
		(legacy_teardrops no)
	)
	(paper "A4")
	(title_block
		(title "peb — Lightning_PEB_BRD.brd")
		(comment 1 "Lightning (Wiwynn / Facebook NVMe JBOF) / footprints 1724-1730 of 2563")
	)
	(layers
		(0 "F.Cu" signal "TOP")
		(4 "In1.Cu" signal "L2GND")
		(6 "In2.Cu" signal "L3")
		(8 "In3.Cu" signal "L4VCC")
		(10 "In4.Cu" signal "L5VCC")
		(12 "In5.Cu" signal "L6")
		(14 "In6.Cu" signal "L7GND")
		(2 "B.Cu" signal "BOTTOM")
		(9 "F.Adhes" user "F.Adhesive")
		(11 "B.Adhes" user "B.Adhesive")
		(13 "F.Paste" user "Package Geometry/Pastemask Top")
		(15 "B.Paste" user "Package Geometry/Pastemask Bottom")
		(5 "F.SilkS" user "Ref Des/Silkscreen Top")
		(7 "B.SilkS" user "Ref Des/Silkscreen Bottom")
		(1 "F.Mask" user "Board Geometry/Soldermask Top")
		(3 "B.Mask" user "Board Geometry/Soldermask Bottom")
		(17 "Dwgs.User" user "User.Drawings")
		(19 "Cmts.User" user "User.Comments")
		(21 "Eco1.User" user "User.Eco1")
		(23 "Eco2.User" user "User.Eco2")
		(25 "Edge.Cuts" user "Board Geometry/Outline")
		(27 "Margin" user)
		(31 "F.CrtYd" user "Package Geometry/Place Bound Top")
		(29 "B.CrtYd" user "Package Geometry/Place Bound Bottom")
		(35 "F.Fab" user "Ref Des/Assembly Top")
		(33 "B.Fab" user "Ref Des/Assembly Bottom")
	)
	(footprint ""
		(layer "B.Cu")
		(at 271.4625 -4.7625 180)
		(property "Reference" "R389"
			(at 0 0 0)
			(layer "B.SilkS")
			(hide yes)
			(effects
				(font
					(size 1.27 1.27)
				)
				(justify mirror)
			)
		)
		(property "Value" "0R2J-2-GP"
			(at -0.064008 -3.993896 180)
			(unlocked yes)
			(layer "B.Fab")
			(hide yes)
			(effects
				(font
					(size 1.016 1.016)
					(thickness 0.1524)
				)
				(justify mirror)
			)
		)
		(property "Device Type" "R402H16"
			(at -0.064008 -5.517896 180)
			(unlocked yes)
			(layer "B.Fab")
			(hide yes)
			(effects
				(font
					(size 1.016 1.016)
					(thickness 0.1524)
				)
				(justify mirror)
			)
		)
		(duplicate_pad_numbers_are_jumpers no)
		(fp_line
			(start 0.508 -0.9398)
			(end 0.508 0.9398)
			(stroke
				(width 0.1524)
				(type default)
			)
			(layer "B.SilkS")
		)
		(fp_line
			(start -0.508 -0.9398)
			(end 0.508 -0.9398)
			(stroke
				(width 0.1524)
				(type default)
			)
			(layer "B.SilkS")
		)
		(fp_rect
			(start 0.508 0.9398)
			(end -0.508 -0.9398)
			(stroke
				(width 0)
				(type default)
			)
			(fill no)
			(layer "B.CrtYd")
		)
		(fp_rect
			(start 0.508 0.9398)
			(end -0.508 -0.9398)
			(stroke
				(width 0)
				(type default)
			)
			(fill no)
			(layer "B.Fab")
		)
		(pad "1" smd custom
			(at 0 -0.4445)
			(size 0.1397 0.1397)
			(layers "B.Cu" "B.Mask" "B.Paste")
			(net "MINISAS_CN16_C_I2C_INT#")
			(options
				(clearance outline)
				(anchor circle)
			)
			(primitives
				(gr_poly
					(pts
						(arc
							(start -0.1778 0.2794)
							(mid -0.249642 0.249642)
							(end -0.2794 0.1778)
						)
						(arc
							(start -0.2794 -0.1778)
							(mid -0.249642 -0.249642)
							(end -0.1778 -0.2794)
						)
						(arc
							(start 0.1778 -0.2794)
							(mid 0.249642 -0.249642)
							(end 0.2794 -0.1778)
						)
						(arc
							(start 0.2794 0.1778)
							(mid 0.249642 0.249642)
							(end 0.1778 0.2794)
						)
					)
					(width 0)
					(fill yes)
				)
			)
		)
		(pad "2" smd custom
			(at 0 0.4445)
			(size 0.1397 0.1397)
			(layers "B.Cu" "B.Mask" "B.Paste")
			(net "PCIE_REFCLK_H1_N_R")
			(options
				(clearance outline)
				(anchor circle)
			)
			(primitives
				(gr_poly
					(pts
						(arc
							(start -0.1778 0.2794)
							(mid -0.249642 0.249642)
							(end -0.2794 0.1778)
						)
						(arc
							(start -0.2794 -0.1778)
							(mid -0.249642 -0.249642)
							(end -0.1778 -0.2794)
						)
						(arc
							(start 0.1778 -0.2794)
							(mid 0.249642 -0.249642)
							(end 0.2794 -0.1778)
						)
						(arc
							(start 0.2794 0.1778)
							(mid 0.249642 0.249642)
							(end 0.1778 0.2794)
						)
					)
					(width 0)
					(fill yes)
				)
			)
		)
	)
	(footprint ""
		(layer "B.Cu")
		(at 247.1166 -41.995852 -90)
		(property "Reference" "C453"
			(at 0 0 90)
			(layer "B.SilkS")
			(hide yes)
			(effects
				(font
					(size 1.27 1.27)
				)
				(justify mirror)
			)
		)
		(property "Value" "SCD1U16V1KX-1-GP"
			(at 2.8321 -1.7399 270)
			(unlocked yes)
			(layer "B.Fab")
			(hide yes)
			(effects
				(font
					(size 1.016 1.016)
					(thickness 0.1524)
				)
				(justify mirror)
			)
		)
		(property "Device Type" "C0201H13"
			(at 2.8321 -3.2639 270)
			(unlocked yes)
			(layer "B.Fab")
			(hide yes)
			(effects
				(font
					(size 1.016 1.016)
					(thickness 0.1524)
				)
				(justify mirror)
			)
		)
		(duplicate_pad_numbers_are_jumpers no)
		(fp_rect
			(start 0.2794 0.6477)
			(end -0.2794 -0.6477)
			(stroke
				(width 0)
				(type default)
			)
			(fill no)
			(layer "B.CrtYd")
		)
		(fp_rect
			(start 0.2794 0.6477)
			(end -0.2794 -0.6477)
			(stroke
				(width 0)
				(type default)
			)
			(fill no)
			(layer "B.Fab")
		)
		(pad "1" smd custom
			(at 0 -0.2794 90)
			(size 0.0762 0.0762)
			(layers "B.Cu" "B.Mask" "B.Paste")
			(net "DUT_VDD")
			(options
				(clearance outline)
				(anchor circle)
			)
			(primitives
				(gr_poly
					(pts
						(arc
							(start 0.1524 0.127)
							(mid 0.137521 0.162921)
							(end 0.1016 0.1778)
						)
						(arc
							(start -0.1016 0.1778)
							(mid -0.137521 0.162921)
							(end -0.1524 0.127)
						)
						(arc
							(start -0.1524 -0.127)
							(mid -0.137521 -0.162921)
							(end -0.1016 -0.1778)
						)
						(arc
							(start 0.1016 -0.1778)
							(mid 0.137521 -0.162921)
							(end 0.1524 -0.127)
						)
					)
					(width 0)
					(fill yes)
				)
			)
		)
		(pad "2" smd custom
			(at 0 0.2794 90)
			(size 0.0762 0.0762)
			(layers "B.Cu" "B.Mask" "B.Paste")
			(net "GND")
			(options
				(clearance outline)
				(anchor circle)
			)
			(primitives
				(gr_poly
					(pts
						(arc
							(start 0.1524 0.127)
							(mid 0.137521 0.162921)
							(end 0.1016 0.1778)
						)
						(arc
							(start -0.1016 0.1778)
							(mid -0.137521 0.162921)
							(end -0.1524 0.127)
						)
						(arc
							(start -0.1524 -0.127)
							(mid -0.137521 -0.162921)
							(end -0.1016 -0.1778)
						)
						(arc
							(start 0.1016 -0.1778)
							(mid 0.137521 -0.162921)
							(end 0.1524 -0.127)
						)
					)
					(width 0)
					(fill yes)
				)
			)
		)
	)
	(footprint ""
		(layer "B.Cu")
		(at 13.50518 -76.661264 90)
		(property "Reference" "C621"
			(at 0 0 90)
			(layer "B.SilkS")
			(hide yes)
			(effects
				(font
					(size 1.27 1.27)
				)
				(justify mirror)
			)
		)
		(property "Value" "SCD1U16V2KX-3GP"
			(at -1.1811 -2.7051 90)
			(unlocked yes)
			(layer "B.Fab")
			(hide yes)
			(effects
				(font
					(size 1.016 1.016)
					(thickness 0.1524)
				)
				(justify mirror)
			)
		)
		(property "Device Type" "C402H22"
			(at -1.1811 -4.2291 90)
			(unlocked yes)
			(layer "B.Fab")
			(hide yes)
			(effects
				(font
					(size 1.016 1.016)
					(thickness 0.1524)
				)
				(justify mirror)
			)
		)
		(duplicate_pad_numbers_are_jumpers no)
		(fp_rect
			(start 0.4318 0.9525)
			(end -0.4318 -0.9525)
			(stroke
				(width 0)
				(type default)
			)
			(fill no)
			(layer "B.CrtYd")
		)
		(fp_rect
			(start 0.4318 0.9525)
			(end -0.4318 -0.9525)
			(stroke
				(width 0)
				(type default)
			)
			(fill no)
			(layer "B.Fab")
		)
		(pad "1" smd custom
			(at 0 -0.4445 270)
			(size 0.1524 0.1524)
			(layers "B.Cu" "B.Mask" "B.Paste")
			(net "P1V5_I210")
			(options
				(clearance outline)
				(anchor circle)
			)
			(primitives
				(gr_poly
					(pts
						(arc
							(start 0.3048 0.2032)
							(mid 0.275042 0.275042)
							(end 0.2032 0.3048)
						)
						(arc
							(start -0.2032 0.3048)
							(mid -0.275042 0.275042)
							(end -0.3048 0.2032)
						)
						(arc
							(start -0.3048 -0.2032)
							(mid -0.275042 -0.275042)
							(end -0.2032 -0.3048)
						)
						(arc
							(start 0.2032 -0.3048)
							(mid 0.275042 -0.275042)
							(end 0.3048 -0.2032)
						)
					)
					(width 0)
					(fill yes)
				)
			)
		)
		(pad "2" smd custom
			(at 0 0.4445 270)
			(size 0.1524 0.1524)
			(layers "B.Cu" "B.Mask" "B.Paste")
			(net "GND")
			(options
				(clearance outline)
				(anchor circle)
			)
			(primitives
				(gr_poly
					(pts
						(arc
							(start 0.3048 0.2032)
							(mid 0.275042 0.275042)
							(end 0.2032 0.3048)
						)
						(arc
							(start -0.2032 0.3048)
							(mid -0.275042 0.275042)
							(end -0.3048 0.2032)
						)
						(arc
							(start -0.3048 -0.2032)
							(mid -0.275042 -0.275042)
							(end -0.2032 -0.3048)
						)
						(arc
							(start 0.2032 -0.3048)
							(mid 0.275042 -0.275042)
							(end 0.3048 -0.2032)
						)
					)
					(width 0)
					(fill yes)
				)
			)
		)
	)
	(footprint ""
		(layer "B.Cu")
		(at 164.084 -33.528)
		(property "Reference" "R2921"
			(at 0 0 0)
			(layer "B.SilkS")
			(hide yes)
			(effects
				(font
					(size 1.27 1.27)
				)
				(justify mirror)
			)
		)
		(property "Value" "0R2J-2-GP"
			(at -0.064008 -3.993896 0)
			(unlocked yes)
			(layer "B.Fab")
			(hide yes)
			(effects
				(font
					(size 1.016 1.016)
					(thickness 0.1524)
				)
				(justify mirror)
			)
		)
		(property "Device Type" "R402H16"
			(at -0.064008 -5.517896 0)
			(unlocked yes)
			(layer "B.Fab")
			(hide yes)
			(effects
				(font
					(size 1.016 1.016)
					(thickness 0.1524)
				)
				(justify mirror)
			)
		)
		(duplicate_pad_numbers_are_jumpers no)
		(fp_line
			(start -0.508 -0.9398)
			(end 0.508 -0.9398)
			(stroke
				(width 0.1524)
				(type default)
			)
			(layer "B.SilkS")
		)
		(fp_line
			(start 0.508 -0.9398)
			(end 0.508 0.9398)
			(stroke
				(width 0.1524)
				(type default)
			)
			(layer "B.SilkS")
		)
		(fp_rect
			(start 0.508 0.9398)
			(end -0.508 -0.9398)
			(stroke
				(width 0)
				(type default)
			)
			(fill no)
			(layer "B.CrtYd")
		)
		(fp_rect
			(start 0.508 0.9398)
			(end -0.508 -0.9398)
			(stroke
				(width 0)
				(type default)
			)
			(fill no)
			(layer "B.Fab")
		)
		(pad "1" smd custom
			(at 0 -0.4445 180)
			(size 0.1397 0.1397)
			(layers "B.Cu" "B.Mask" "B.Paste")
			(net "BMC_I2C4_MINI4_SDA")
			(options
				(clearance outline)
				(anchor circle)
			)
			(primitives
				(gr_poly
					(pts
						(arc
							(start -0.1778 0.2794)
							(mid -0.249642 0.249642)
							(end -0.2794 0.1778)
						)
						(arc
							(start -0.2794 -0.1778)
							(mid -0.249642 -0.249642)
							(end -0.1778 -0.2794)
						)
						(arc
							(start 0.1778 -0.2794)
							(mid 0.249642 -0.249642)
							(end 0.2794 -0.1778)
						)
						(arc
							(start 0.2794 0.1778)
							(mid 0.249642 0.249642)
							(end 0.1778 0.2794)
						)
					)
					(width 0)
					(fill yes)
				)
			)
		)
		(pad "2" smd custom
			(at 0 0.4445 180)
			(size 0.1397 0.1397)
			(layers "B.Cu" "B.Mask" "B.Paste")
			(net "8644_SDA_R_4")
			(options
				(clearance outline)
				(anchor circle)
			)
			(primitives
				(gr_poly
					(pts
						(arc
							(start -0.1778 0.2794)
							(mid -0.249642 0.249642)
							(end -0.2794 0.1778)
						)
						(arc
							(start -0.2794 -0.1778)
							(mid -0.249642 -0.249642)
							(end -0.1778 -0.2794)
						)
						(arc
							(start 0.1778 -0.2794)
							(mid 0.249642 -0.249642)
							(end 0.2794 -0.1778)
						)
						(arc
							(start 0.2794 0.1778)
							(mid 0.249642 0.249642)
							(end 0.1778 0.2794)
						)
					)
					(width 0)
					(fill yes)
				)
			)
		)
	)
	(footprint ""
		(layer "B.Cu")
		(at 221.0816 -199.9996)
		(property "Reference" "R157"
			(at 0 0 0)
			(layer "B.SilkS")
			(hide yes)
			(effects
				(font
					(size 1.27 1.27)
				)
				(justify mirror)
			)
		)
		(property "Value" "4K7R2F-GP"
			(at -0.064008 -3.993896 0)
			(unlocked yes)
			(layer "B.Fab")
			(hide yes)
			(effects
				(font
					(size 1.016 1.016)
					(thickness 0.1524)
				)
				(justify mirror)
			)
		)
		(property "Device Type" "R402H16"
			(at -0.064008 -5.517896 0)
			(unlocked yes)
			(layer "B.Fab")
			(hide yes)
			(effects
				(font
					(size 1.016 1.016)
					(thickness 0.1524)
				)
				(justify mirror)
			)
		)
		(duplicate_pad_numbers_are_jumpers no)
		(fp_line
			(start -0.508 -0.9398)
			(end 0.508 -0.9398)
			(stroke
				(width 0.1524)
				(type default)
			)
			(layer "B.SilkS")
		)
		(fp_line
			(start 0.508 -0.9398)
			(end 0.508 0.9398)
			(stroke
				(width 0.1524)
				(type default)
			)
			(layer "B.SilkS")
		)
		(fp_rect
			(start 0.508 0.9398)
			(end -0.508 -0.9398)
			(stroke
				(width 0)
				(type default)
			)
			(fill no)
			(layer "B.CrtYd")
		)
		(fp_rect
			(start 0.508 0.9398)
			(end -0.508 -0.9398)
			(stroke
				(width 0)
				(type default)
			)
			(fill no)
			(layer "B.Fab")
		)
		(pad "1" smd custom
			(at 0 -0.4445 180)
			(size 0.1397 0.1397)
			(layers "B.Cu" "B.Mask" "B.Paste")
			(net "BMC_SSD_RST#0_A8")
			(options
				(clearance outline)
				(anchor circle)
			)
			(primitives
				(gr_poly
					(pts
						(arc
							(start -0.1778 0.2794)
							(mid -0.249642 0.249642)
							(end -0.2794 0.1778)
						)
						(arc
							(start -0.2794 -0.1778)
							(mid -0.249642 -0.249642)
							(end -0.1778 -0.2794)
						)
						(arc
							(start 0.1778 -0.2794)
							(mid 0.249642 -0.249642)
							(end 0.2794 -0.1778)
						)
						(arc
							(start 0.2794 0.1778)
							(mid 0.249642 0.249642)
							(end 0.1778 0.2794)
						)
					)
					(width 0)
					(fill yes)
				)
			)
		)
		(pad "2" smd custom
			(at 0 0.4445 180)
			(size 0.1397 0.1397)
			(layers "B.Cu" "B.Mask" "B.Paste")
			(net "P3V3_STBY")
			(options
				(clearance outline)
				(anchor circle)
			)
			(primitives
				(gr_poly
					(pts
						(arc
							(start -0.1778 0.2794)
							(mid -0.249642 0.249642)
							(end -0.2794 0.1778)
						)
						(arc
							(start -0.2794 -0.1778)
							(mid -0.249642 -0.249642)
							(end -0.1778 -0.2794)
						)
						(arc
							(start 0.1778 -0.2794)
							(mid 0.249642 -0.249642)
							(end 0.2794 -0.1778)
						)
						(arc
							(start 0.2794 0.1778)
							(mid 0.249642 0.249642)
							(end 0.1778 0.2794)
						)
					)
					(width 0)
					(fill yes)
				)
			)
		)
	)
	(footprint ""
		(layer "B.Cu")
		(at 297.591988 -35.059112 180)
		(property "Reference" "C256"
			(at 0 0 0)
			(layer "B.SilkS")
			(hide yes)
			(effects
				(font
					(size 1.27 1.27)
				)
				(justify mirror)
			)
		)
		(property "Value" "SCD1U10V2KX-5GP"
			(at -1.1811 -2.7051 180)
			(unlocked yes)
			(layer "B.Fab")
			(hide yes)
			(effects
				(font
					(size 1.016 1.016)
					(thickness 0.1524)
				)
				(justify mirror)
			)
		)
		(property "Device Type" "C402H22"
			(at -1.1811 -4.2291 180)
			(unlocked yes)
			(layer "B.Fab")
			(hide yes)
			(effects
				(font
					(size 1.016 1.016)
					(thickness 0.1524)
				)
				(justify mirror)
			)
		)
		(duplicate_pad_numbers_are_jumpers no)
		(fp_rect
			(start 0.4318 0.9525)
			(end -0.4318 -0.9525)
			(stroke
				(width 0)
				(type default)
			)
			(fill no)
			(layer "B.CrtYd")
		)
		(fp_rect
			(start 0.4318 0.9525)
			(end -0.4318 -0.9525)
			(stroke
				(width 0)
				(type default)
			)
			(fill no)
			(layer "B.Fab")
		)
		(pad "1" smd custom
			(at 0 -0.4445)
			(size 0.1524 0.1524)
			(layers "B.Cu" "B.Mask" "B.Paste")
			(net "GND")
			(options
				(clearance outline)
				(anchor circle)
			)
			(primitives
				(gr_poly
					(pts
						(arc
							(start 0.3048 0.2032)
							(mid 0.275042 0.275042)
							(end 0.2032 0.3048)
						)
						(arc
							(start -0.2032 0.3048)
							(mid -0.275042 0.275042)
							(end -0.3048 0.2032)
						)
						(arc
							(start -0.3048 -0.2032)
							(mid -0.275042 -0.275042)
							(end -0.2032 -0.3048)
						)
						(arc
							(start 0.2032 -0.3048)
							(mid 0.275042 -0.275042)
							(end 0.3048 -0.2032)
						)
					)
					(width 0)
					(fill yes)
				)
			)
		)
		(pad "2" smd custom
			(at 0 0.4445)
			(size 0.1524 0.1524)
			(layers "B.Cu" "B.Mask" "B.Paste")
			(net "P3V3_STBY")
			(options
				(clearance outline)
				(anchor circle)
			)
			(primitives
				(gr_poly
					(pts
						(arc
							(start 0.3048 0.2032)
							(mid 0.275042 0.275042)
							(end 0.2032 0.3048)
						)
						(arc
							(start -0.2032 0.3048)
							(mid -0.275042 0.275042)
							(end -0.3048 0.2032)
						)
						(arc
							(start -0.3048 -0.2032)
							(mid -0.275042 -0.275042)
							(end -0.2032 -0.3048)
						)
						(arc
							(start 0.2032 -0.3048)
							(mid 0.275042 -0.275042)
							(end 0.3048 -0.2032)
						)
					)
					(width 0)
					(fill yes)
				)
			)
		)
	)
	(footprint ""
		(layer "B.Cu")
		(at 51.470052 -110.70463)
		(property "Reference" "R325"
			(at 0 0 0)
			(layer "B.SilkS")
			(hide yes)
			(effects
				(font
					(size 1.27 1.27)
				)
				(justify mirror)
			)
		)
		(property "Value" "4K7R2F-GP"
			(at -0.064008 -3.993896 0)
			(unlocked yes)
			(layer "B.Fab")
			(hide yes)
			(effects
				(font
					(size 1.016 1.016)
					(thickness 0.1524)
				)
				(justify mirror)
			)
		)
		(property "Device Type" "R402H16"
			(at -0.064008 -5.517896 0)
			(unlocked yes)
			(layer "B.Fab")
			(hide yes)
			(effects
				(font
					(size 1.016 1.016)
					(thickness 0.1524)
				)
				(justify mirror)
			)
		)
		(duplicate_pad_numbers_are_jumpers no)
		(fp_line
			(start -0.508 -0.9398)
			(end 0.508 -0.9398)
			(stroke
				(width 0.1524)
				(type default)
			)
			(layer "B.SilkS")
		)
		(fp_line
			(start 0.508 -0.9398)
			(end 0.508 0.9398)
			(stroke
				(width 0.1524)
				(type default)
			)
			(layer "B.SilkS")
		)
		(fp_rect
			(start 0.508 0.9398)
			(end -0.508 -0.9398)
			(stroke
				(width 0)
				(type default)
			)
			(fill no)
			(layer "B.CrtYd")
		)
		(fp_rect
			(start 0.508 0.9398)
			(end -0.508 -0.9398)
			(stroke
				(width 0)
				(type default)
			)
			(fill no)
			(layer "B.Fab")
		)
		(pad "1" smd custom
			(at 0 -0.4445 180)
			(size 0.1397 0.1397)
			(layers "B.Cu" "B.Mask" "B.Paste")
			(net "P3V3_STBY")
			(options
				(clearance outline)
				(anchor circle)
			)
			(primitives
				(gr_poly
					(pts
						(arc
							(start -0.1778 0.2794)
							(mid -0.249642 0.249642)
							(end -0.2794 0.1778)
						)
						(arc
							(start -0.2794 -0.1778)
							(mid -0.249642 -0.249642)
							(end -0.1778 -0.2794)
						)
						(arc
							(start 0.1778 -0.2794)
							(mid 0.249642 -0.249642)
							(end 0.2794 -0.1778)
						)
						(arc
							(start 0.2794 0.1778)
							(mid 0.249642 0.249642)
							(end 0.1778 0.2794)
						)
					)
					(width 0)
					(fill yes)
				)
			)
		)
		(pad "2" smd custom
			(at 0 0.4445 180)
			(size 0.1397 0.1397)
			(layers "B.Cu" "B.Mask" "B.Paste")
			(net "I2C6_LS_G2")
			(options
				(clearance outline)
				(anchor circle)
			)
			(primitives
				(gr_poly
					(pts
						(arc
							(start -0.1778 0.2794)
							(mid -0.249642 0.249642)
							(end -0.2794 0.1778)
						)
						(arc
							(start -0.2794 -0.1778)
							(mid -0.249642 -0.249642)
							(end -0.1778 -0.2794)
						)
						(arc
							(start 0.1778 -0.2794)
							(mid 0.249642 -0.249642)
							(end 0.2794 -0.1778)
						)
						(arc
							(start 0.2794 0.1778)
							(mid 0.249642 0.249642)
							(end 0.1778 0.2794)
						)
					)
					(width 0)
					(fill yes)
				)
			)
		)
	)
)
